FILE_TYPE = CONNECTIVITY;
{Allegro Design Entry HDL 16.6-p007 (v16-6-112F) 10/10/2012}
"PAGE_NUMBER" = 76;
0"NC";
1"GND\g";
2"GND\g";
3"GND\g";
4"GND\g";
5"GND\g";
6"PVCCIN_CPU1\g";
7"PVCCIN_CPU1\g";
8"PVCCIN_CPU1\g";
9"PVCCIN_CPU1\g";
10"PVCCIN_CPU1\g";
11"PVCCIN_CPU1\g";
12"PVCCIN_CPU1\g";
13"PVCCIN_CPU1\g";
14"PVCCIN_CPU1\g";
15"PVCCIN_CPU1\g";
16"PVCCIN_CPU1\g";
17"GND\g";
18"PVCCMCP_CPU1\g";
19"PVCCMCP_CPU1\g";
20"PVCCIO_CPU1\g";
21"GND\g";
22"PVCCMCP_CPU1\g";
23"GND\g";
24"GND\g";
25"GND\g";
26"GND\g";
27"PVSA_CPU1\g";
28"PVCCIO_CPU1\g";
29"GND\g";
30"PVSA_CPU1\g";
31"GND\g";
32"GND\g";
33"PVCCIN_CPU1\g";
34"GND\g";
35"GND\g";
36"GND\g";
37"GND\g";
38"GND\g";
%"CAP_A"
"1","(-1275,4450)","0","dev_discrete","I1";
;
ROOM"PVCCIN_CPU1_DECAP_VR"
$SEC"1"
CDS_SEC"1"
CDS_LIB"dev_discrete"
BOM_COST"PROC"
CDS_LOCATION"C3D21"
MATERIAL"X6S"
VOLTAGE"4V"
PACK_TYPE"0603V"
TOLERANCE"20%"
VALUE"22.0UF"
PART_NUMBER"E15431-004"
LOCATION"C3D21";
"B"
$PN"2"21;
"A"
$PN"1"18;
%"CAP_A"
"1","(-3250,4425)","0","dev_discrete","I10";
;
ROOM"PVCCIN_CPU1_DECAP_VR"
$SEC"1"
CDS_SEC"1"
CDS_LIB"dev_discrete"
BOM_COST"PROC"
CDS_LOCATION"C2D40"
MATERIAL"X6S"
VOLTAGE"4V"
PACK_TYPE"0603V"
TOLERANCE"20%"
VALUE"22.0UF"
PART_NUMBER"E15431-004"
LOCATION"C2D40";
"B"
$PN"2"21;
"A"
$PN"1"18;
%"CAP"
"1","(-5300,1550)","0","mstr_discrete","I100";
;
ROOM"PVCCIN_CPU1_DECAP_VR"
CDS_LOCATION"C7P2"
$SEC"1"
CDS_SEC"1"
BOM_COST"PROC"
CDS_LIB"mstr_discrete"
MATERIAL"X6S"
VOLTAGE"4V"
PACK_TYPE"0805"
TOLERANCE"20%"
VALUE"47UF"
PART_NUMBER"C95333-006"
LOCATION"C7P2";
"A"
$PN"1"14;
"B"
$PN"2"37;
%"CAP"
"1","(-5625,1550)","0","mstr_discrete","I101";
;
ROOM"PVCCIN_CPU1_DECAP_VR"
CDS_LOCATION"C8P3"
$SEC"1"
CDS_SEC"1"
BOM_COST"PROC"
CDS_LIB"mstr_discrete"
MATERIAL"X6S"
VOLTAGE"4V"
PACK_TYPE"0805"
TOLERANCE"20%"
VALUE"47UF"
PART_NUMBER"C95333-006"
LOCATION"C8P3";
"A"
$PN"1"14;
"B"
$PN"2"37;
%"CAP"
"1","(-5975,1550)","0","mstr_discrete","I103";
;
ROOM"PVCCIN_CPU1_DECAP_VR"
CDS_LOCATION"C8P19"
$SEC"1"
CDS_SEC"1"
BOM_COST"PROC"
CDS_LIB"mstr_discrete"
MATERIAL"X6S"
VOLTAGE"4V"
PACK_TYPE"0805"
TOLERANCE"20%"
VALUE"47UF"
PART_NUMBER"C95333-006"
LOCATION"C8P19";
"A"
$PN"1"14;
"B"
$PN"2"37;
%"CAP"
"1","(-5275,875)","0","mstr_discrete","I105";
;
ROOM"PVCCIN_CPU1_DECAP_VR"
CDS_LOCATION"C7P1"
$SEC"1"
CDS_SEC"1"
CDS_LIB"mstr_discrete"
BOM_COST"PROC"
MATERIAL"X6S"
VOLTAGE"4V"
PACK_TYPE"0805"
TOLERANCE"20%"
VALUE"47UF"
PART_NUMBER"C95333-006"
LOCATION"C7P1";
"A"
$PN"1"15;
"B"
$PN"2"38;
%"CAP"
"1","(-5600,875)","0","mstr_discrete","I106";
;
ROOM"PVCCIN_CPU1_DECAP_VR"
CDS_LOCATION"C8P34"
$SEC"1"
CDS_SEC"1"
CDS_LIB"mstr_discrete"
BOM_COST"PROC"
MATERIAL"X6S"
VOLTAGE"4V"
PACK_TYPE"0805"
TOLERANCE"20%"
VALUE"47UF"
PART_NUMBER"C95333-006"
LOCATION"C8P34";
"A"
$PN"1"15;
"B"
$PN"2"38;
%"CAP"
"1","(-5950,875)","0","mstr_discrete","I107";
;
ROOM"PVCCIN_CPU1_DECAP_VR"
CDS_LOCATION"C8P12"
$SEC"1"
CDS_SEC"1"
CDS_LIB"mstr_discrete"
BOM_COST"PROC"
MATERIAL"X6S"
VOLTAGE"4V"
PACK_TYPE"0805"
TOLERANCE"20%"
VALUE"47UF"
PART_NUMBER"C95333-006"
LOCATION"C8P12";
"A"
$PN"1"15;
"B"
$PN"2"38;
%"CAP_A"
"1","(-6300,3775)","0","dev_discrete","I108";
;
ROOM"PVCCIN_CPU1_DECAP_VR"
$SEC"1"
CDS_SEC"1"
CDS_LIB"dev_discrete"
BOM_COST"PROC"
CDS_LOCATION"C2D26"
MATERIAL"X6S"
VOLTAGE"4V"
PACK_TYPE"0603V"
TOLERANCE"20%"
VALUE"22.0UF"
PART_NUMBER"E15431-004"
LOCATION"C2D26";
"B"
$PN"2"1;
"A"
$PN"1"7;
%"GND"
"1","(-6300,3450)","0","mstr_symbols","I109";
;
HDL_POWER"GND"
ROOM"PVCCIN_CPU1_DECAP_VR"
BODY_TYPE"PLUMBING"
SIZE"1B"
CDS_LIB"mstr_symbols"
VOLTAGE"0";
"A\NAC"1;
%"CAP_A"
"1","(-7000,3775)","0","dev_discrete","I111";
;
ROOM"PVCCIN_CPU1_DECAP_VR"
$SEC"1"
CDS_SEC"1"
CDS_LIB"dev_discrete"
BOM_COST"PROC"
CDS_LOCATION"C3D1"
MATERIAL"X6S"
VOLTAGE"4V"
PACK_TYPE"0603V"
TOLERANCE"20%"
VALUE"22.0UF"
PART_NUMBER"E15431-004"
LOCATION"C3D1";
"B"
$PN"2"1;
"A"
$PN"1"7;
%"CAP_A"
"1","(-6250,3150)","0","dev_discrete","I112";
;
ROOM"PVCCIN_CPU1_DECAP_VR"
$SEC"1"
CDS_SEC"1"
CDS_LIB"dev_discrete"
BOM_COST"PROC"
CDS_LOCATION"C2D23"
MATERIAL"X6S"
VOLTAGE"4V"
PACK_TYPE"0603V"
TOLERANCE"20%"
VALUE"22.0UF"
PART_NUMBER"E15431-004"
LOCATION"C2D23";
"B"
$PN"2"2;
"A"
$PN"1"8;
%"GND"
"1","(-6250,2825)","0","mstr_symbols","I113";
;
HDL_POWER"GND"
ROOM"PVCCIN_CPU1_DECAP_VR"
BODY_TYPE"PLUMBING"
SIZE"1B"
CDS_LIB"mstr_symbols"
VOLTAGE"0";
"A\NAC"2;
%"CAP_A"
"1","(-6600,3125)","0","dev_discrete","I114";
;
ROOM"PVCCIN_CPU1_DECAP_VR"
$SEC"1"
CDS_SEC"1"
CDS_LIB"dev_discrete"
BOM_COST"PROC"
CDS_LOCATION"C2D17"
MATERIAL"X6S"
VOLTAGE"4V"
PACK_TYPE"0603V"
TOLERANCE"20%"
VALUE"22.0UF"
PART_NUMBER"E15431-004"
LOCATION"C2D17";
"B"
$PN"2"2;
"A"
$PN"1"8;
%"CAP_A"
"1","(-6950,3150)","0","dev_discrete","I116";
;
ROOM"PVCCIN_CPU1_DECAP_VR"
$SEC"1"
CDS_SEC"1"
CDS_LIB"dev_discrete"
BOM_COST"PROC"
CDS_LOCATION"C2D1"
MATERIAL"X6S"
VOLTAGE"4V"
PACK_TYPE"0603V"
TOLERANCE"20%"
VALUE"22.0UF"
PART_NUMBER"E15431-004"
LOCATION"C2D1";
"B"
$PN"2"2;
"A"
$PN"1"8;
%"CAP"
"1","(-7050,2200)","0","mstr_discrete","I118";
;
ROOM"PVCCIN_CPU1_DECAP_VR"
CDS_LOCATION"C8P26"
$SEC"1"
CDS_SEC"1"
BOM_COST"PROC"
CDS_LIB"mstr_discrete"
MATERIAL"X6S"
VOLTAGE"4V"
PACK_TYPE"0805"
TOLERANCE"20%"
VALUE"47UF"
PART_NUMBER"C95333-006"
LOCATION"C8P26";
"A"
$PN"1"12;
"B"
$PN"2"3;
%"CAP_A"
"1","(-7325,3775)","0","dev_discrete","I119";
;
ROOM"PVCCIN_CPU1_DECAP_VR"
$SEC"1"
CDS_SEC"1"
CDS_LIB"dev_discrete"
BOM_COST"PROC"
CDS_LOCATION"C2D37"
MATERIAL"X6S"
VOLTAGE"4V"
PACK_TYPE"0603V"
TOLERANCE"20%"
VALUE"22.0UF"
PART_NUMBER"E15431-004"
LOCATION"C2D37";
"B"
$PN"2"1;
"A"
$PN"1"7;
%"CAP_A"
"1","(-7675,3775)","0","dev_discrete","I122";
;
ROOM"PVCCIN_CPU1_DECAP_VR"
$SEC"1"
CDS_SEC"1"
CDS_LIB"dev_discrete"
BOM_COST"PROC"
CDS_LOCATION"C2D34"
MATERIAL"X6S"
VOLTAGE"4V"
PACK_TYPE"0603V"
TOLERANCE"20%"
VALUE"22.0UF"
PART_NUMBER"E15431-004"
LOCATION"C2D34";
"B"
$PN"2"1;
"A"
$PN"1"7;
%"CAP_A"
"1","(-7275,3150)","0","dev_discrete","I123";
;
ROOM"PVCCIN_CPU1_DECAP_VR"
$SEC"1"
CDS_SEC"1"
CDS_LIB"dev_discrete"
BOM_COST"PROC"
CDS_LOCATION"C2D45"
MATERIAL"X6S"
VOLTAGE"4V"
PACK_TYPE"0603V"
TOLERANCE"20%"
VALUE"22.0UF"
PART_NUMBER"E15431-004"
LOCATION"C2D45";
"B"
$PN"2"2;
"A"
$PN"1"8;
%"CAP_A"
"1","(-7625,3150)","0","dev_discrete","I124";
;
ROOM"PVCCIN_CPU1_DECAP_VR"
$SEC"1"
CDS_SEC"1"
CDS_LIB"dev_discrete"
BOM_COST"PROC"
CDS_LOCATION"C2D16"
MATERIAL"X6S"
VOLTAGE"4V"
PACK_TYPE"0603V"
TOLERANCE"20%"
VALUE"22.0UF"
PART_NUMBER"E15431-004"
LOCATION"C2D16";
"B"
$PN"2"2;
"A"
$PN"1"8;
%"CAP"
"1","(-7375,2200)","0","mstr_discrete","I125";
;
ROOM"PVCCIN_CPU1_DECAP_VR"
CDS_LOCATION"C8P29"
$SEC"1"
CDS_SEC"1"
BOM_COST"PROC"
CDS_LIB"mstr_discrete"
MATERIAL"X6S"
VOLTAGE"4V"
PACK_TYPE"0805"
TOLERANCE"20%"
VALUE"47UF"
PART_NUMBER"C95333-006"
LOCATION"C8P29";
"A"
$PN"1"12;
"B"
$PN"2"3;
%"CAP"
"1","(-7725,2200)","0","mstr_discrete","I127";
;
ROOM"PVCCIN_CPU1_DECAP_VR"
CDS_LOCATION"C8P10"
$SEC"1"
CDS_SEC"1"
BOM_COST"PROC"
CDS_LIB"mstr_discrete"
VOLTAGE"4V"
MATERIAL"X6S"
PACK_TYPE"0805"
TOLERANCE"20%"
VALUE"47UF"
PART_NUMBER"C95333-006"
LOCATION"C8P10";
"A"
$PN"1"12;
"B"
$PN"2"3;
%"GND"
"1","(-6350,1875)","0","mstr_symbols","I128";
;
HDL_POWER"GND"
ROOM"PVCCIN_CPU1_DECAP_VR"
BODY_TYPE"PLUMBING"
CDS_LIB"mstr_symbols"
SIZE"1B"
VOLTAGE"0";
"A\NAC"3;
%"CAP"
"1","(-6350,1550)","0","mstr_discrete","I129";
;
ROOM"PVCCIN_CPU1_DECAP_VR"
CDS_LOCATION"C8P16"
$SEC"1"
CDS_SEC"1"
CDS_LIB"mstr_discrete"
BOM_COST"PROC"
MATERIAL"X6S"
VOLTAGE"4V"
PACK_TYPE"0805"
TOLERANCE"20%"
VALUE"47UF"
PART_NUMBER"C95333-006"
LOCATION"C8P16";
"A"
$PN"1"13;
"B"
$PN"2"4;
%"GND"
"1","(-6350,1225)","0","mstr_symbols","I130";
;
HDL_POWER"GND"
ROOM"PVCCIN_CPU1_DECAP_VR"
BODY_TYPE"PLUMBING"
CDS_LIB"mstr_symbols"
SIZE"1B"
VOLTAGE"0";
"A\NAC"4;
%"CAP"
"1","(-6700,1550)","0","mstr_discrete","I131";
;
ROOM"PVCCIN_CPU1_DECAP_VR"
CDS_LOCATION"C8P33"
$SEC"1"
CDS_SEC"1"
CDS_LIB"mstr_discrete"
BOM_COST"PROC"
MATERIAL"X6S"
VOLTAGE"4V"
PACK_TYPE"0805"
TOLERANCE"20%"
VALUE"47UF"
PART_NUMBER"C95333-006"
LOCATION"C8P33";
"A"
$PN"1"13;
"B"
$PN"2"4;
%"CAP"
"1","(-7050,1550)","0","mstr_discrete","I132";
;
ROOM"PVCCIN_CPU1_DECAP_VR"
CDS_LOCATION"C8P13"
$SEC"1"
CDS_SEC"1"
CDS_LIB"mstr_discrete"
BOM_COST"PROC"
MATERIAL"X6S"
VOLTAGE"4V"
PACK_TYPE"0805"
TOLERANCE"20%"
VALUE"47UF"
PART_NUMBER"C95333-006"
LOCATION"C8P13";
"A"
$PN"1"13;
"B"
$PN"2"4;
%"CAP"
"1","(-6350,900)","0","mstr_discrete","I133";
;
ROOM"PVCCIN_CPU1_DECAP_VR"
CDS_LOCATION"C8P17"
$SEC"1"
CDS_SEC"1"
CDS_LIB"mstr_discrete"
BOM_COST"PROC"
MATERIAL"X6S"
VOLTAGE"4V"
PACK_TYPE"0805"
TOLERANCE"20%"
VALUE"47UF"
PART_NUMBER"C95333-006"
LOCATION"C8P17";
"A"
$PN"1"16;
"B"
$PN"2"5;
%"GND"
"1","(-6350,575)","0","mstr_symbols","I134";
;
HDL_POWER"GND"
ROOM"PVCCIN_CPU1_DECAP_VR"
BODY_TYPE"PLUMBING"
SIZE"1B"
CDS_LIB"mstr_symbols"
VOLTAGE"0";
"A\NAC"5;
%"CAP"
"1","(-6700,900)","0","mstr_discrete","I135";
;
ROOM"PVCCIN_CPU1_DECAP_VR"
CDS_LOCATION"C8P21"
$SEC"1"
CDS_SEC"1"
CDS_LIB"mstr_discrete"
BOM_COST"PROC"
MATERIAL"X6S"
VOLTAGE"4V"
PACK_TYPE"0805"
TOLERANCE"20%"
VALUE"47UF"
PART_NUMBER"C95333-006"
LOCATION"C8P21";
"A"
$PN"1"16;
"B"
$PN"2"5;
%"CAP"
"1","(-7050,900)","0","mstr_discrete","I136";
;
ROOM"PVCCIN_CPU1_DECAP_VR"
CDS_LOCATION"C8P25"
$SEC"1"
CDS_SEC"1"
CDS_LIB"mstr_discrete"
BOM_COST"PROC"
MATERIAL"X6S"
VOLTAGE"4V"
PACK_TYPE"0805"
TOLERANCE"20%"
VALUE"47UF"
PART_NUMBER"C95333-006"
LOCATION"C8P25";
"A"
$PN"1"16;
"B"
$PN"2"5;
%"CAP"
"1","(-7375,1550)","0","mstr_discrete","I137";
;
ROOM"PVCCIN_CPU1_DECAP_VR"
CDS_LOCATION"C8P28"
$SEC"1"
CDS_SEC"1"
CDS_LIB"mstr_discrete"
BOM_COST"PROC"
MATERIAL"X6S"
VOLTAGE"4V"
PACK_TYPE"0805"
TOLERANCE"20%"
VALUE"47UF"
PART_NUMBER"C95333-006"
LOCATION"C8P28";
"A"
$PN"1"13;
"B"
$PN"2"4;
%"CAP"
"1","(-7725,1550)","0","mstr_discrete","I139";
;
ROOM"PVCCIN_CPU1_DECAP_VR"
CDS_LOCATION"C8P11"
$SEC"1"
CDS_SEC"1"
BOM_COST"PROC"
CDS_LIB"mstr_discrete"
MATERIAL"X6S"
VOLTAGE"4V"
PACK_TYPE"0805"
TOLERANCE"20%"
VALUE"47UF"
PART_NUMBER"C95333-006"
LOCATION"C8P11";
"A"
$PN"1"13;
"B"
$PN"2"4;
%"CAP"
"1","(-7375,900)","0","mstr_discrete","I141";
;
ROOM"PVCCIN_CPU1_DECAP_VR"
CDS_LOCATION"C8P27"
$SEC"1"
CDS_SEC"1"
CDS_LIB"mstr_discrete"
BOM_COST"PROC"
MATERIAL"X6S"
VOLTAGE"4V"
PACK_TYPE"0805"
TOLERANCE"20%"
VALUE"47UF"
PART_NUMBER"C95333-006"
LOCATION"C8P27";
"A"
$PN"1"16;
"B"
$PN"2"5;
%"PVCCIN_CPU1"
"1","(-5900,4725)","0","mstr_symbols","I143";
;
HDL_POWER"PVCCIN_CPU1"
ROOM"PVCCIN_CPU1_DECAP_VR"
BODY_TYPE"PLUMBING"
CDS_LIB"mstr_symbols"
VOLTAGE"2.0V";
"G\NAC"6;
%"PVCCIN_CPU1"
"1","(-7675,4050)","0","mstr_symbols","I144";
;
HDL_POWER"PVCCIN_CPU1"
ROOM"PVCCIN_CPU1_DECAP_VR"
BODY_TYPE"PLUMBING"
CDS_LIB"mstr_symbols"
VOLTAGE"2.0V";
"G\NAC"7;
%"PVCCIN_CPU1"
"1","(-7625,3425)","0","mstr_symbols","I145";
;
HDL_POWER"PVCCIN_CPU1"
ROOM"PVCCIN_CPU1_DECAP_VR"
BODY_TYPE"PLUMBING"
CDS_LIB"mstr_symbols"
VOLTAGE"2.0V";
"G\NAC"8;
%"PVCCIN_CPU1"
"1","(-5875,4050)","0","mstr_symbols","I146";
;
HDL_POWER"PVCCIN_CPU1"
ROOM"PVCCIN_CPU1_DECAP_VR"
BODY_TYPE"PLUMBING"
CDS_LIB"mstr_symbols"
VOLTAGE"2.0V";
"G\NAC"9;
%"PVCCIN_CPU1"
"1","(-5850,3425)","0","mstr_symbols","I147";
;
HDL_POWER"PVCCIN_CPU1"
ROOM"PVCCIN_CPU1_DECAP_VR"
BODY_TYPE"PLUMBING"
CDS_LIB"mstr_symbols"
VOLTAGE"2.0V";
"G\NAC"10;
%"CAP_A"
"1","(-2450,3750)","0","dev_discrete","I15";
;
ROOM"PVCCIN_CPU1_DECAP_VR"
$SEC"1"
CDS_SEC"1"
CDS_LIB"dev_discrete"
BOM_COST"PROC"
CDS_LOCATION"C3D9"
MATERIAL"X6S"
VOLTAGE"4V"
PACK_TYPE"0603V"
TOLERANCE"20%"
VALUE"22.0UF"
PART_NUMBER"E15431-004"
LOCATION"C3D9";
"B"
$PN"2"17;
"A"
$PN"1"20;
%"PVCCIN_CPU1"
"1","(-5975,2475)","0","mstr_symbols","I153";
;
HDL_POWER"PVCCIN_CPU1"
ROOM"PVCCIN_CPU1_DECAP_VR"
BODY_TYPE"PLUMBING"
CDS_LIB"mstr_symbols"
VOLTAGE"2.0V";
"G\NAC"11;
%"PVCCIN_CPU1"
"1","(-7725,2475)","0","mstr_symbols","I154";
;
HDL_POWER"PVCCIN_CPU1"
ROOM"PVCCIN_CPU1_DECAP_VR"
BODY_TYPE"PLUMBING"
CDS_LIB"mstr_symbols"
VOLTAGE"2.0V";
"G\NAC"12;
%"PVCCIN_CPU1"
"1","(-7725,1825)","0","mstr_symbols","I155";
;
HDL_POWER"PVCCIN_CPU1"
ROOM"PVCCIN_CPU1_DECAP_VR"
BODY_TYPE"PLUMBING"
CDS_LIB"mstr_symbols"
VOLTAGE"2.0V";
"G\NAC"13;
%"PVCCIN_CPU1"
"1","(-5975,1825)","0","mstr_symbols","I156";
;
HDL_POWER"PVCCIN_CPU1"
ROOM"PVCCIN_CPU1_DECAP_VR"
BODY_TYPE"PLUMBING"
CDS_LIB"mstr_symbols"
VOLTAGE"2.0V";
"G\NAC"14;
%"PVCCIN_CPU1"
"1","(-5950,1150)","0","mstr_symbols","I157";
;
HDL_POWER"PVCCIN_CPU1"
ROOM"PVCCIN_CPU1_DECAP_VR"
BODY_TYPE"PLUMBING"
CDS_LIB"mstr_symbols"
VOLTAGE"2.0V";
"G\NAC"15;
%"PVCCIN_CPU1"
"1","(-7725,1175)","0","mstr_symbols","I158";
;
HDL_POWER"PVCCIN_CPU1"
ROOM"PVCCIN_CPU1_DECAP_VR"
BODY_TYPE"PLUMBING"
CDS_LIB"mstr_symbols"
VOLTAGE"2.0V";
"G\NAC"16;
%"CAP_A"
"1","(-4325,4425)","0","dev_discrete","I159";
;
ROOM"PVCCIN_CPU1_DECAP_VR"
$SEC"1"
CDS_SEC"1"
CDS_LIB"dev_discrete"
BOM_COST"PROC"
CDS_LOCATION"C2D15"
MATERIAL"X6S"
VOLTAGE"4V"
PACK_TYPE"0603V"
TOLERANCE"20%"
VALUE"22.0UF"
PART_NUMBER"E15431-004"
LOCATION"C2D15";
"B"
$PN"2"31;
"A"
$PN"1"6;
%"GND"
"1","(-2450,3425)","0","mstr_symbols","I16";
;
HDL_POWER"GND"
ROOM"PVCCIN_CPU1_DECAP_VR"
BODY_TYPE"PLUMBING"
SIZE"1B"
CDS_LIB"mstr_symbols"
VOLTAGE"0";
"A\NAC"17;
%"CAP_A"
"1","(-4325,3750)","0","dev_discrete","I160";
;
ROOM"PVCCIN_CPU1_DECAP_VR"
$SEC"1"
CDS_SEC"1"
CDS_LIB"dev_discrete"
BOM_COST"PROC"
CDS_LOCATION"C2D38"
MATERIAL"X6S"
VOLTAGE"4V"
PACK_TYPE"0603V"
TOLERANCE"20%"
VALUE"22.0UF"
PART_NUMBER"E15431-004"
LOCATION"C2D38";
"B"
$PN"2"34;
"A"
$PN"1"9;
%"CAP_A"
"1","(-4325,3150)","0","dev_discrete","I161";
;
ROOM"PVCCIN_CPU1_DECAP_VR"
$SEC"1"
CDS_SEC"1"
CDS_LIB"dev_discrete"
BOM_COST"PROC"
CDS_LOCATION"C2D35"
MATERIAL"X6S"
VOLTAGE"4V"
PACK_TYPE"0603V"
TOLERANCE"20%"
VALUE"22.0UF"
PART_NUMBER"E15431-004"
LOCATION"C2D35";
"B"
$PN"2"35;
"A"
$PN"1"10;
%"VCC_CORE"
"1","(-4000,4725)","0","mstr_symbols","I162";
;
CDS_LIB"mstr_symbols"
HDL_POWER"PVCCMCP_CPU1";
"A"18;
%"VCC_CORE"
"1","(-4775,2475)","0","mstr_symbols","I163";
;
CDS_LIB"mstr_symbols"
HDL_POWER"PVCCMCP_CPU1";
"A"19;
%"CAP_A"
"1","(-4000,4450)","0","dev_discrete","I164";
;
ROOM"PVCCIN_CPU1_DECAP_VR"
$SEC"1"
CDS_SEC"1"
CDS_LIB"dev_discrete"
CDS_LOCATION"C3D7"
MATERIAL"X6S"
VOLTAGE"4V"
PACK_TYPE"0603V"
TOLERANCE"20%"
VALUE"22.0UF"
PART_NUMBER"E15431-004"
LOCATION"C3D7";
"B"
$PN"2"21;
"A"
$PN"1"18;
%"CAP_A"
"1","(-3750,4450)","0","dev_discrete","I165";
;
ROOM"PVCCIN_CPU1_DECAP_VR"
$SEC"1"
CDS_SEC"1"
CDS_LIB"dev_discrete"
BOM_COST"PROC"
CDS_LOCATION"C2D39"
MATERIAL"X6S"
VOLTAGE"4V"
PACK_TYPE"0603V"
TOLERANCE"20%"
VALUE"22.0UF"
PART_NUMBER"E15431-004"
LOCATION"C2D39";
"B"
$PN"2"21;
"A"
$PN"1"18;
%"CAP_A"
"1","(-3500,4450)","0","dev_discrete","I166";
;
ROOM"PVCCIN_CPU1_DECAP_VR"
$SEC"1"
CDS_SEC"1"
CDS_LIB"dev_discrete"
BOM_COST"PROC"
CDS_LOCATION"C3D17"
MATERIAL"X6S"
VOLTAGE"4V"
PACK_TYPE"0603V"
TOLERANCE"20%"
VALUE"22.0UF"
PART_NUMBER"E15431-004"
LOCATION"C3D17";
"B"
$PN"2"21;
"A"
$PN"1"18;
%"PVCCIO_CPU1"
"1","(-3975,4025)","0","mstr_symbols","I167";
;
HDL_POWER"PVCCIO_CPU1"
BODY_TYPE"PLUMBING"
CDS_LIB"mstr_symbols"
VOLTAGE"1.1V";
"G\NAC"20;
%"CAP_A"
"1","(-975,4450)","0","dev_discrete","I169";
;
ROOM"PVCCIN_CPU1_DECAP_VR"
$SEC"1"
CDS_SEC"1"
CDS_LIB"dev_discrete"
BOM_COST"PROC"
CDS_LOCATION"C3D18"
MATERIAL"X6S"
VOLTAGE"4V"
PACK_TYPE"0603V"
TOLERANCE"20%"
VALUE"22.0UF"
PART_NUMBER"E15431-004"
LOCATION"C3D18";
"B"
$PN"2"21;
"A"
$PN"1"18;
%"CAP_A"
"1","(-725,4450)","0","dev_discrete","I170";
;
ROOM"PVCCIN_CPU1_DECAP_VR"
$SEC"1"
CDS_SEC"1"
CDS_LIB"dev_discrete"
BOM_COST"PROC"
CDS_LOCATION"C3D6"
MATERIAL"X6S"
VOLTAGE"4V"
PACK_TYPE"0603V"
TOLERANCE"20%"
VALUE"22.0UF"
PART_NUMBER"E15431-004"
LOCATION"C3D6";
"B"
$PN"2"21;
"A"
$PN"1"18;
%"CAP_A"
"1","(-2725,4450)","0","dev_discrete","I171";
;
ROOM"PVCCIN_CPU1_DECAP_VR"
$SEC"1"
CDS_SEC"1"
CDS_LIB"dev_discrete"
BOM_COST"PROC"
CDS_LOCATION"C3D14"
MATERIAL"X6S"
VOLTAGE"4V"
PACK_TYPE"0603V"
TOLERANCE"20%"
VALUE"22.0UF"
PART_NUMBER"E15431-004"
LOCATION"C3D14";
"B"
$PN"2"21;
"A"
$PN"1"18;
%"CAP_A"
"1","(-3975,3750)","0","dev_discrete","I172";
;
ROOM"PVCCIN_CPU1_DECAP_VR"
$SEC"1"
CDS_SEC"1"
CDS_LIB"dev_discrete"
BOM_COST"PROC"
CDS_LOCATION"C3D23"
MATERIAL"X6S"
VOLTAGE"4V"
PACK_TYPE"0603V"
TOLERANCE"20%"
VALUE"22.0UF"
PART_NUMBER"E15431-004"
LOCATION"C3D23";
"B"
$PN"2"17;
"A"
$PN"1"20;
%"CAP_A"
"1","(-3675,3750)","0","dev_discrete","I174";
;
ROOM"PVCCIN_CPU1_DECAP_VR"
$SEC"1"
CDS_SEC"1"
CDS_LIB"dev_discrete"
BOM_COST"PROC"
CDS_LOCATION"C3D15"
MATERIAL"X6S"
VOLTAGE"4V"
PACK_TYPE"0603V"
TOLERANCE"20%"
VALUE"22.0UF"
PART_NUMBER"E15431-004"
LOCATION"C3D15";
"B"
$PN"2"17;
"A"
$PN"1"20;
%"CAP_A"
"1","(-3350,3775)","0","dev_discrete","I175";
;
ROOM"PVCCIN_CPU1_DECAP_VR"
$SEC"1"
CDS_SEC"1"
CDS_LIB"dev_discrete"
BOM_COST"PROC"
CDS_LOCATION"C3D24"
MATERIAL"X6S"
VOLTAGE"4V"
PACK_TYPE"0603V"
TOLERANCE"20%"
VALUE"22.0UF"
PART_NUMBER"E15431-004"
LOCATION"C3D24";
"B"
$PN"2"17;
"A"
$PN"1"20;
%"CAP_A"
"1","(-3050,3775)","0","dev_discrete","I176";
;
ROOM"PVCCIN_CPU1_DECAP_VR"
$SEC"1"
CDS_SEC"1"
CDS_LIB"dev_discrete"
BOM_COST"PROC"
CDS_LOCATION"C3D16"
MATERIAL"X6S"
VOLTAGE"4V"
PACK_TYPE"0603V"
TOLERANCE"20%"
VALUE"22.0UF"
PART_NUMBER"E15431-004"
LOCATION"C3D16";
"B"
$PN"2"17;
"A"
$PN"1"20;
%"CAP_A"
"1","(-2375,925)","0","dev_discrete","I179";
;
ROOM"PVCCIN_CPU1_DECAP_VR"
$SEC"1"
CDS_SEC"1"
CDS_LIB"dev_discrete"
BOM_COST"PROC"
CDS_LOCATION"C7P12"
MATERIAL"X6S"
VOLTAGE"4V"
PACK_TYPE"0603V"
TOLERANCE"20%"
VALUE"22.0UF"
PART_NUMBER"E15431-004"
LOCATION"C7P12";
"B"
$PN"2"25;
"A"
$PN"1"28;
%"CAP_A"
"1","(-2750,3775)","0","dev_discrete","I18";
;
ROOM"PVCCIN_CPU1_DECAP_VR"
$SEC"1"
CDS_SEC"1"
CDS_LIB"dev_discrete"
BOM_COST"PROC"
CDS_LOCATION"C3D8"
MATERIAL"X6S"
VOLTAGE"4V"
PACK_TYPE"0603V"
TOLERANCE"20%"
VALUE"22.0UF"
PART_NUMBER"E15431-004"
LOCATION"C3D8";
"B"
$PN"2"17;
"A"
$PN"1"20;
%"CAP"
"1","(-4775,2150)","0","mstr_discrete","I181";
;
CDS_SEC"1"
ROOM"PVCCIN_CPU1_DECAP_VR"
CDS_LOCATION"C7P9"
SEC"1"
SEC_TYPE"0805"
CDS_LIB"mstr_discrete"
BOM_COST"PROC"
MATERIAL"X6S"
VOLTAGE"4V"
PACK_TYPE"0805"
TOLERANCE"20%"
VALUE"47UF"
PART_NUMBER"C95333-006"
LOCATION"C7P9";
"A"
$PN"1"19;
"B"
$PN"2"24;
%"CAP"
"1","(-4525,2150)","0","mstr_discrete","I182";
;
ROOM"PVCCIN_CPU1_DECAP_VR"
CDS_LOCATION"C7P5"
$SEC"1"
CDS_SEC"1"
BOM_COST"PROC"
CDS_LIB"mstr_discrete"
VOLTAGE"4V"
MATERIAL"X6S"
PACK_TYPE"0805"
TOLERANCE"20%"
VALUE"47UF"
PART_NUMBER"C95333-006"
LOCATION"C7P5";
"A"
$PN"1"19;
"B"
$PN"2"24;
%"CAP"
"1","(-3425,2150)","0","mstr_discrete","I183";
;
ROOM"PVCCIN_CPU1_DECAP_VR"
CDS_LOCATION"C7P11"
$SEC"1"
CDS_SEC"1"
BOM_COST"PROC"
CDS_LIB"mstr_discrete"
VOLTAGE"4V"
MATERIAL"X6S"
PACK_TYPE"0805"
TOLERANCE"20%"
VALUE"47UF"
PART_NUMBER"C95333-006"
LOCATION"C7P11";
"A"
$PN"1"19;
"B"
$PN"2"24;
%"CAP"
"1","(-3175,2150)","0","mstr_discrete","I184";
;
ROOM"PVCCIN_CPU1_DECAP_VR"
CDS_LOCATION"C7P8"
$SEC"1"
CDS_SEC"1"
BOM_COST"PROC"
CDS_LIB"mstr_discrete"
VOLTAGE"4V"
MATERIAL"X6S"
PACK_TYPE"0805"
TOLERANCE"20%"
VALUE"47UF"
PART_NUMBER"C95333-006"
LOCATION"C7P8";
"A"
$PN"1"19;
"B"
$PN"2"24;
%"CAP"
"1","(-1450,2125)","0","mstr_discrete","I195";
;
ROOM"PVCCIN_CPU1_DECAP_VR"
CDS_LOCATION"C7P4"
$SEC"1"
CDS_SEC"1"
CDS_LIB"mstr_discrete"
BOM_COST"PROC"
MATERIAL"X6S"
VOLTAGE"4V"
PACK_TYPE"0805"
TOLERANCE"20%"
VALUE"47UF"
PART_NUMBER"C95333-006"
LOCATION"C7P4";
"A"
$PN"1"19;
"B"
$PN"2"24;
%"CAP_A"
"1","(-1950,3725)","0","dev_discrete","I196";
;
ROOM"PVCCIN_CPU1_DECAP_VR"
$SEC"1"
CDS_SEC"1"
CDS_LIB"dev_discrete"
BOM_COST"PROC"
CDS_LOCATION"C3D10"
MATERIAL"X6S"
VOLTAGE"4V"
PACK_TYPE"0603V"
TOLERANCE"20%"
VALUE"22.0UF"
PART_NUMBER"E15431-004"
LOCATION"C3D10";
"B"
$PN"2"23;
"A"
$PN"1"22;
%"CAP_A"
"1","(-1700,3725)","0","dev_discrete","I197";
;
ROOM"PVCCIN_CPU1_DECAP_VR"
$SEC"1"
CDS_SEC"1"
CDS_LIB"dev_discrete"
BOM_COST"PROC"
CDS_LOCATION"C2D18"
MATERIAL"X6S"
VOLTAGE"4V"
PACK_TYPE"0603V"
TOLERANCE"20%"
VALUE"22.0UF"
PART_NUMBER"E15431-004"
LOCATION"C2D18";
"B"
$PN"2"23;
"A"
$PN"1"22;
%"CAP_A"
"1","(-1450,3725)","0","dev_discrete","I198";
;
ROOM"PVCCIN_CPU1_DECAP_VR"
$SEC"1"
CDS_SEC"1"
CDS_LIB"dev_discrete"
BOM_COST"PROC"
CDS_LOCATION"C2D28"
MATERIAL"X6S"
VOLTAGE"4V"
PACK_TYPE"0603V"
TOLERANCE"20%"
VALUE"22.0UF"
PART_NUMBER"E15431-004"
LOCATION"C2D28";
"B"
$PN"2"23;
"A"
$PN"1"22;
%"CAP_A"
"1","(-1200,3725)","0","dev_discrete","I199";
;
ROOM"PVCCIN_CPU1_DECAP_VR"
$SEC"1"
CDS_SEC"1"
CDS_LIB"dev_discrete"
BOM_COST"PROC"
CDS_LOCATION"C2D29"
MATERIAL"X6S"
VOLTAGE"4V"
PACK_TYPE"0603V"
TOLERANCE"20%"
VALUE"22.0UF"
PART_NUMBER"E15431-004"
LOCATION"C2D29";
"B"
$PN"2"23;
"A"
$PN"1"22;
%"GND"
"1","(-725,4100)","0","mstr_symbols","I2";
;
HDL_POWER"GND"
ROOM"PVCCIN_CPU1_DECAP_VR"
BODY_TYPE"PLUMBING"
CDS_LIB"mstr_symbols"
SIZE"1B"
VOLTAGE"0";
"A\NAC"21;
%"CAP_A"
"1","(-7725,4450)","0","dev_discrete","I201";
;
ROOM"PVCCIN_CPU1_DECAP_VR"
$SEC"1"
CDS_SEC"1"
CDS_LIB"dev_discrete"
BOM_COST"PROC"
CDS_LOCATION"C2D2"
MATERIAL"X6S"
VOLTAGE"4V"
PACK_TYPE"0603V"
TOLERANCE"20%"
VALUE"22.0UF"
PART_NUMBER"E15431-004"
LOCATION"C2D2";
"B"
$PN"2"32;
"A"
$PN"1"33;
%"CAP_A"
"1","(-6675,4450)","0","dev_discrete","I202";
;
ROOM"PVCCIN_CPU1_DECAP_VR"
$SEC"1"
CDS_SEC"1"
CDS_LIB"dev_discrete"
BOM_COST"PROC"
CDS_LOCATION"C2D3"
MATERIAL"X6S"
VOLTAGE"4V"
PACK_TYPE"0603V"
TOLERANCE"20%"
VALUE"22.0UF"
PART_NUMBER"E15431-004"
LOCATION"C2D3";
"B"
$PN"2"32;
"A"
$PN"1"33;
%"CAP_A"
"1","(-6650,3775)","0","dev_discrete","I203";
;
ROOM"PVCCIN_CPU1_DECAP_VR"
$SEC"1"
CDS_SEC"1"
CDS_LIB"dev_discrete"
BOM_COST"PROC"
CDS_LOCATION"C2D47"
MATERIAL"X6S"
VOLTAGE"4V"
PACK_TYPE"0603V"
TOLERANCE"20%"
VALUE"22.0UF"
PART_NUMBER"E15431-004"
LOCATION"C2D47";
"B"
$PN"2"1;
"A"
$PN"1"7;
%"CAP_A"
"1","(-5275,4450)","0","dev_discrete","I204";
;
ROOM"PVCCIN_CPU1_DECAP_VR"
$SEC"1"
CDS_SEC"1"
CDS_LIB"dev_discrete"
BOM_COST"PROC"
CDS_LOCATION"C2D46"
MATERIAL"X6S"
VOLTAGE"4V"
PACK_TYPE"0603V"
TOLERANCE"20%"
VALUE"22.0UF"
PART_NUMBER"E15431-004"
LOCATION"C2D46";
"B"
$PN"2"31;
"A"
$PN"1"6;
%"CAP_A"
"1","(-5500,3150)","0","dev_discrete","I205";
;
ROOM"PVCCIN_CPU1_DECAP_VR"
$SEC"1"
CDS_SEC"1"
CDS_LIB"dev_discrete"
BOM_COST"PROC"
CDS_LOCATION"C3D25"
MATERIAL"X6S"
VOLTAGE"4V"
PACK_TYPE"0603V"
TOLERANCE"20%"
VALUE"22.0UF"
PART_NUMBER"E15431-004"
LOCATION"C3D25";
"B"
$PN"2"35;
"A"
$PN"1"10;
%"CAP_A"
"1","(-2100,925)","0","dev_discrete","I206";
;
ROOM"PVCCIN_CPU1_DECAP_VR"
$SEC"1"
CDS_SEC"1"
CDS_LIB"dev_discrete"
BOM_COST"PROC"
CDS_LOCATION"C7P16"
MATERIAL"X6S"
VOLTAGE"4V"
PACK_TYPE"0603V"
TOLERANCE"20%"
VALUE"22.0UF"
PART_NUMBER"E15431-004"
LOCATION"C7P16";
"B"
$PN"2"25;
"A"
$PN"1"28;
%"CAP_A"
"1","(-725,3700)","0","dev_discrete","I207";
;
ROOM"PVCCIN_CPU1_DECAP_VR"
$SEC"1"
CDS_SEC"1"
CDS_LIB"dev_discrete"
BOM_COST"PROC"
CDS_LOCATION"C3D20"
MATERIAL"X6S"
VOLTAGE"4V"
PACK_TYPE"0603V"
TOLERANCE"20%"
VALUE"22.0UF"
PART_NUMBER"E15431-004"
LOCATION"C3D20";
"B"
$PN"2"23;
"A"
$PN"1"22;
%"CAP_A"
"1","(-950,3725)","0","dev_discrete","I208";
;
ROOM"PVCCIN_CPU1_DECAP_VR"
$SEC"1"
CDS_SEC"1"
CDS_LIB"dev_discrete"
BOM_COST"PROC"
CDS_LOCATION"C3D19"
MATERIAL"X6S"
VOLTAGE"4V"
PACK_TYPE"0603V"
TOLERANCE"20%"
VALUE"22.0UF"
PART_NUMBER"E15431-004"
LOCATION"C3D19";
"B"
$PN"2"23;
"A"
$PN"1"22;
%"VCC_CORE"
"1","(-1950,3975)","0","mstr_symbols","I209";
;
CDS_LIB"mstr_symbols"
HDL_POWER"PVCCMCP_CPU1";
"A"22;
%"GND"
"1","(-725,3400)","0","mstr_symbols","I210";
;
HDL_POWER"GND"
ROOM"PVCCIN_CPU1_DECAP_VR"
BODY_TYPE"PLUMBING"
SIZE"1B"
CDS_LIB"mstr_symbols"
VOLTAGE"0";
"A\NAC"23;
%"CAP"
"1","(-975,2150)","0","mstr_discrete","I211";
;
ROOM"PVCCIN_CPU1_DECAP_VR"
CDS_LOCATION"C8P14"
$SEC"1"
CDS_SEC"1"
CDS_LIB"mstr_discrete"
BOM_COST"PROC"
MATERIAL"X6S"
VOLTAGE"4V"
PACK_TYPE"0805"
TOLERANCE"20%"
VALUE"47UF"
PART_NUMBER"C95333-006"
LOCATION"C8P14";
"A"
$PN"1"19;
"B"
$PN"2"24;
%"CAP"
"1","(-1225,2150)","0","mstr_discrete","I212";
;
ROOM"PVCCIN_CPU1_DECAP_VR"
CDS_LOCATION"C8P15"
$SEC"1"
CDS_SEC"1"
CDS_LIB"mstr_discrete"
BOM_COST"PROC"
MATERIAL"X6S"
VOLTAGE"4V"
PACK_TYPE"0805"
TOLERANCE"20%"
VALUE"47UF"
PART_NUMBER"C95333-006"
LOCATION"C8P15";
"A"
$PN"1"19;
"B"
$PN"2"24;
%"CAP"
"1","(-500,2100)","0","mstr_discrete","I213";
;
ROOM"PVCCIN_CPU1_DECAP_VR"
CDS_LOCATION"C8P8"
$SEC"1"
CDS_SEC"1"
BOM_COST"PROC"
CDS_LIB"mstr_discrete"
MATERIAL"X6S"
VOLTAGE"4V"
PACK_TYPE"0805"
TOLERANCE"20%"
VALUE"47UF"
PART_NUMBER"C95333-006"
LOCATION"C8P8";
"A"
$PN"1"19;
"B"
$PN"2"24;
%"CAP"
"1","(-700,2150)","0","mstr_discrete","I214";
;
ROOM"PVCCIN_CPU1_DECAP_VR"
CDS_LOCATION"C8P9"
$SEC"1"
CDS_SEC"1"
CDS_LIB"mstr_discrete"
BOM_COST"PROC"
MATERIAL"X6S"
VOLTAGE"4V"
PACK_TYPE"0805"
TOLERANCE"20%"
VALUE"47UF"
PART_NUMBER"C95333-006"
LOCATION"C8P9";
"A"
$PN"1"19;
"B"
$PN"2"24;
%"CAP"
"1","(-6700,2200)","0","mstr_discrete","I215";
;
ROOM"PVCCIN_CPU1_DECAP_VR"
CDS_LOCATION"C7P19"
$SEC"1"
CDS_SEC"1"
BOM_COST"PROC"
CDS_LIB"mstr_discrete"
MATERIAL"X6S"
VOLTAGE"4V"
PACK_TYPE"0805"
TOLERANCE"20%"
VALUE"47UF"
PART_NUMBER"C95333-006"
LOCATION"C7P19";
"A"
$PN"1"12;
"B"
$PN"2"3;
%"CAP"
"1","(-6350,2200)","0","mstr_discrete","I216";
;
ROOM"PVCCIN_CPU1_DECAP_VR"
CDS_LOCATION"C8P32"
$SEC"1"
CDS_SEC"1"
BOM_COST"PROC"
CDS_LIB"mstr_discrete"
MATERIAL"X6S"
VOLTAGE"4V"
PACK_TYPE"0805"
TOLERANCE"20%"
VALUE"47UF"
PART_NUMBER"C95333-006"
LOCATION"C8P32";
"A"
$PN"1"12;
"B"
$PN"2"3;
%"CAP"
"1","(-7725,900)","0","mstr_discrete","I217";
;
ROOM"PVCCIN_CPU1_DECAP_VR"
CDS_LOCATION"C8P24"
$SEC"1"
CDS_SEC"1"
BOM_COST"PROC"
CDS_LIB"mstr_discrete"
MATERIAL"X6S"
VOLTAGE"4V"
PACK_TYPE"0805"
TOLERANCE"20%"
VALUE"47UF"
PART_NUMBER"C95333-006"
LOCATION"C8P24";
"A"
$PN"1"16;
"B"
$PN"2"5;
%"CAP"
"1","(-5150,2200)","0","mstr_discrete","I218";
;
ROOM"PVCCIN_CPU1_DECAP_VR"
CDS_LOCATION"C7P20"
$SEC"1"
CDS_SEC"1"
CDS_LIB"mstr_discrete"
BOM_COST"PROC"
MATERIAL"X6S"
VOLTAGE"4V"
PACK_TYPE"0805"
TOLERANCE"20%"
VALUE"47UF"
PART_NUMBER"C95333-006"
LOCATION"C7P20";
"A"
$PN"1"11;
"B"
$PN"2"36;
%"CAP"
"1","(-1750,2125)","0","mstr_discrete","I23";
;
ROOM"PVCCIN_CPU1_DECAP_VR"
CDS_LOCATION"C7P6"
$SEC"1"
CDS_SEC"1"
BOM_COST"PROC"
CDS_LIB"mstr_discrete"
MATERIAL"X6S"
VOLTAGE"4V"
PACK_TYPE"0805"
TOLERANCE"20%"
VALUE"47UF"
PART_NUMBER"C95333-006"
LOCATION"C7P6";
"A"
$PN"1"19;
"B"
$PN"2"24;
%"GND"
"1","(-500,1725)","0","mstr_symbols","I24";
;
HDL_POWER"GND"
ROOM"PVCCIN_CPU1_DECAP_VR"
BODY_TYPE"PLUMBING"
SIZE"1B"
CDS_LIB"mstr_symbols"
VOLTAGE"0";
"A\NAC"24;
%"CAP"
"1","(-2025,2150)","0","mstr_discrete","I25";
;
ROOM"PVCCIN_CPU1_DECAP_VR"
CDS_LOCATION"C7P13"
$SEC"1"
CDS_SEC"1"
BOM_COST"PROC"
CDS_LIB"mstr_discrete"
MATERIAL"X6S"
VOLTAGE"4V"
PACK_TYPE"0805"
TOLERANCE"20%"
VALUE"47UF"
PART_NUMBER"C95333-006"
LOCATION"C7P13";
"A"
$PN"1"19;
"B"
$PN"2"24;
%"CAP"
"1","(-2325,2150)","0","mstr_discrete","I26";
;
ROOM"PVCCIN_CPU1_DECAP_VR"
CDS_LOCATION"C7P10"
$SEC"1"
CDS_SEC"1"
BOM_COST"PROC"
CDS_LIB"mstr_discrete"
MATERIAL"X6S"
VOLTAGE"4V"
PACK_TYPE"0805"
TOLERANCE"20%"
VALUE"47UF"
PART_NUMBER"C95333-006"
LOCATION"C7P10";
"A"
$PN"1"19;
"B"
$PN"2"24;
%"CAP"
"1","(-2625,2150)","0","mstr_discrete","I27";
;
ROOM"PVCCIN_CPU1_DECAP_VR"
CDS_LOCATION"C7P7"
$SEC"1"
CDS_SEC"1"
BOM_COST"PROC"
CDS_LIB"mstr_discrete"
MATERIAL"X6S"
VOLTAGE"4V"
PACK_TYPE"0805"
TOLERANCE"20%"
VALUE"47UF"
PART_NUMBER"C95333-006"
LOCATION"C7P7";
"A"
$PN"1"19;
"B"
$PN"2"24;
%"CAP"
"1","(-2925,2150)","0","mstr_discrete","I28";
;
ROOM"PVCCIN_CPU1_DECAP_VR"
CDS_LOCATION"C8P22"
$SEC"1"
CDS_SEC"1"
BOM_COST"PROC"
CDS_LIB"mstr_discrete"
MATERIAL"X6S"
VOLTAGE"4V"
PACK_TYPE"0805"
TOLERANCE"20%"
VALUE"47UF"
PART_NUMBER"C95333-006"
LOCATION"C8P22";
"A"
$PN"1"19;
"B"
$PN"2"24;
%"CAP"
"1","(-2625,925)","0","mstr_discrete","I29";
;
ROOM"PVCCIN_CPU1_DECAP_VR"
CDS_LOCATION"C7P17"
$SEC"1"
CDS_SEC"1"
CDS_LIB"mstr_discrete"
BOM_COST"PROC"
MATERIAL"X6S"
VOLTAGE"4V"
PACK_TYPE"0805"
TOLERANCE"20%"
VALUE"47UF"
PART_NUMBER"C95333-006"
LOCATION"C7P17";
"A"
$PN"1"28;
"B"
$PN"2"25;
%"CAP_A"
"1","(-1600,4450)","0","dev_discrete","I3";
;
ROOM"PVCCIN_CPU1_DECAP_VR"
$SEC"1"
CDS_SEC"1"
CDS_LIB"dev_discrete"
BOM_COST"PROC"
CDS_LOCATION"C3D5"
MATERIAL"X6S"
VOLTAGE"4V"
PACK_TYPE"0603V"
TOLERANCE"20%"
VALUE"22.0UF"
PART_NUMBER"E15431-004"
LOCATION"C3D5";
"B"
$PN"2"21;
"A"
$PN"1"18;
%"GND"
"1","(-2100,600)","0","mstr_symbols","I30";
;
HDL_POWER"GND"
ROOM"PVCCIN_CPU1_DECAP_VR"
BODY_TYPE"PLUMBING"
SIZE"1B"
CDS_LIB"mstr_symbols"
VOLTAGE"0";
"A\NAC"25;
%"CAP"
"1","(-2750,3050)","0","mstr_discrete","I33";
;
ROOM"PVCCIN_CPU1_DECAP_VR"
CDS_LOCATION"C2D8"
$SEC"1"
CDS_SEC"1"
CDS_LIB"mstr_discrete"
BOM_COST"PROC"
MATERIAL"X6S"
VOLTAGE"4V"
PACK_TYPE"0603LF"
TOLERANCE"20%"
VALUE"10UF"
PART_NUMBER"E15431-001"
LOCATION"C2D8";
"A"
$PN"1"27;
"B"
$PN"2"26;
%"GND"
"1","(-2750,2750)","0","mstr_symbols","I36";
;
HDL_POWER"GND"
ROOM"PVCCIN_CPU1_DECAP_VR"
BODY_TYPE"PLUMBING"
CDS_LIB"mstr_symbols"
SIZE"1B"
VOLTAGE"0";
"A\NAC"26;
%"CAP"
"1","(-3150,3050)","0","mstr_discrete","I37";
;
ROOM"PVCCIN_CPU1_DECAP_VR"
CDS_LOCATION"C2D10"
$SEC"1"
CDS_SEC"1"
CDS_LIB"mstr_discrete"
BOM_COST"PROC"
MATERIAL"X6S"
VOLTAGE"4V"
PACK_TYPE"0603LF"
TOLERANCE"20%"
VALUE"10UF"
PART_NUMBER"E15431-001"
LOCATION"C2D10";
"A"
$PN"1"27;
"B"
$PN"2"26;
%"CAP_A"
"1","(-1875,4450)","0","dev_discrete","I4";
;
ROOM"PVCCIN_CPU1_DECAP_VR"
$SEC"1"
CDS_SEC"1"
CDS_LIB"dev_discrete"
BOM_COST"PROC"
CDS_LOCATION"C3D12"
MATERIAL"X6S"
VOLTAGE"4V"
PACK_TYPE"0603V"
TOLERANCE"20%"
VALUE"22.0UF"
PART_NUMBER"E15431-004"
LOCATION"C3D12";
"B"
$PN"2"21;
"A"
$PN"1"18;
%"PVSA_CPU1"
"1","(-3925,3325)","0","mstr_symbols","I41";
;
HDL_POWER"PVSA_CPU1"
ROOM"PVCCIN_CPU1_DECAP_VR"
BODY_TYPE"PLUMBING"
CDS_LIB"mstr_symbols"
VOLTAGE"1.1V";
"G\NAC"27;
%"CAP"
"1","(-3525,3075)","0","mstr_discrete","I42";
;
ROOM"PVCCIN_CPU1_DECAP_VR"
CDS_LOCATION"C2D11"
$SEC"1"
CDS_SEC"1"
BOM_COST"PROC"
CDS_LIB"mstr_discrete"
MATERIAL"X6S"
VOLTAGE"4V"
PACK_TYPE"0603LF"
TOLERANCE"20%"
VALUE"10UF"
PART_NUMBER"E15431-001"
LOCATION"C2D11";
"A"
$PN"1"27;
"B"
$PN"2"26;
%"CAP"
"1","(-3925,3050)","0","mstr_discrete","I43";
;
ROOM"PVCCIN_CPU1_DECAP_VR"
CDS_LOCATION"C2D9"
$SEC"1"
CDS_SEC"1"
BOM_COST"PROC"
CDS_LIB"mstr_discrete"
MATERIAL"X6S"
VOLTAGE"4V"
PACK_TYPE"0603LF"
TOLERANCE"20%"
VALUE"10UF"
PART_NUMBER"E15431-001"
LOCATION"C2D9";
"A"
$PN"1"27;
"B"
$PN"2"26;
%"CAP"
"1","(-3725,2150)","0","mstr_discrete","I45";
;
ROOM"PVCCIN_CPU1_DECAP_VR"
CDS_LOCATION"C7P15"
$SEC"1"
CDS_SEC"1"
CDS_LIB"mstr_discrete"
BOM_COST"PROC"
MATERIAL"X6S"
VOLTAGE"4V"
PACK_TYPE"0805"
TOLERANCE"20%"
VALUE"47UF"
PART_NUMBER"C95333-006"
LOCATION"C7P15";
"A"
$PN"1"19;
"B"
$PN"2"24;
%"PVCCIO_CPU1"
"1","(-3300,1200)","0","mstr_symbols","I47";
;
HDL_POWER"PVCCIO_CPU1"
BODY_TYPE"PLUMBING"
CDS_LIB"mstr_symbols"
VOLTAGE"1.1V";
"G\NAC"28;
%"CAP"
"1","(-4000,2150)","0","mstr_discrete","I48";
;
ROOM"PVCCIN_CPU1_DECAP_VR"
CDS_LOCATION"C8P23"
$SEC"1"
CDS_SEC"1"
BOM_COST"PROC"
CDS_LIB"mstr_discrete"
MATERIAL"X6S"
VOLTAGE"4V"
PACK_TYPE"0805"
TOLERANCE"20%"
VALUE"47UF"
PART_NUMBER"C95333-006"
LOCATION"C8P23";
"A"
$PN"1"19;
"B"
$PN"2"24;
%"CAP"
"1","(-4275,2125)","0","mstr_discrete","I49";
;
ROOM"PVCCIN_CPU1_DECAP_VR"
CDS_LOCATION"C7P14"
$SEC"1"
CDS_SEC"1"
CDS_LIB"mstr_discrete"
BOM_COST"PROC"
MATERIAL"X6S"
VOLTAGE"4V"
PACK_TYPE"0805"
TOLERANCE"20%"
VALUE"47UF"
PART_NUMBER"C95333-006"
LOCATION"C7P14";
"A"
$PN"1"19;
"B"
$PN"2"24;
%"CAP_A"
"1","(-2175,4450)","0","dev_discrete","I5";
;
ROOM"PVCCIN_CPU1_DECAP_VR"
$SEC"1"
CDS_SEC"1"
CDS_LIB"dev_discrete"
BOM_COST"PROC"
CDS_LOCATION"C3D4"
MATERIAL"X6S"
VOLTAGE"4V"
PACK_TYPE"0603V"
TOLERANCE"20%"
VALUE"22.0UF"
PART_NUMBER"E15431-004"
LOCATION"C3D4";
"B"
$PN"2"21;
"A"
$PN"1"18;
%"CAP"
"1","(-3800,950)","0","mstr_discrete","I50";
;
ROOM"PVCCIN_CPU1_DECAP_VR"
CDS_LOCATION"C8P7"
$SEC"1"
CDS_SEC"1"
BOM_COST"PROC"
CDS_LIB"mstr_discrete"
MATERIAL"X6S"
VOLTAGE"4V"
PACK_TYPE"0805LF"
TOLERANCE"20%"
VALUE"22UF"
PART_NUMBER"C95333-002"
LOCATION"C8P7";
"A"
$PN"1"30;
"B"
$PN"2"29;
%"CAP"
"1","(-2950,925)","0","mstr_discrete","I51";
;
ROOM"PVCCIN_CPU1_DECAP_VR"
CDS_LOCATION"C7P18"
$SEC"1"
CDS_SEC"1"
CDS_LIB"mstr_discrete"
BOM_COST"PROC"
MATERIAL"X6S"
VOLTAGE"4V"
PACK_TYPE"0805"
TOLERANCE"20%"
VALUE"47UF"
PART_NUMBER"C95333-006"
LOCATION"C7P18";
"A"
$PN"1"28;
"B"
$PN"2"25;
%"CAP"
"1","(-3300,925)","0","mstr_discrete","I52";
;
ROOM"PVCCIN_CPU1_DECAP_VR"
CDS_LOCATION"C7P3"
$SEC"1"
CDS_SEC"1"
CDS_LIB"mstr_discrete"
BOM_COST"PROC"
MATERIAL"X6S"
VOLTAGE"4V"
PACK_TYPE"0805"
TOLERANCE"20%"
VALUE"47UF"
PART_NUMBER"C95333-006"
LOCATION"C7P3";
"A"
$PN"1"28;
"B"
$PN"2"25;
%"GND"
"1","(-3800,625)","0","mstr_symbols","I53";
;
HDL_POWER"GND"
ROOM"PVCCIN_CPU1_DECAP_VR"
BODY_TYPE"PLUMBING"
SIZE"1B"
CDS_LIB"mstr_symbols"
VOLTAGE"0";
"A\NAC"29;
%"CAP"
"1","(-4125,950)","0","mstr_discrete","I55";
;
ROOM"PVCCIN_CPU1_DECAP_VR"
CDS_LOCATION"C8P6"
$SEC"1"
CDS_SEC"1"
BOM_COST"PROC"
CDS_LIB"mstr_discrete"
MATERIAL"X6S"
VOLTAGE"4V"
PACK_TYPE"0805LF"
TOLERANCE"20%"
VALUE"22UF"
PART_NUMBER"C95333-002"
LOCATION"C8P6";
"A"
$PN"1"30;
"B"
$PN"2"29;
%"PVSA_CPU1"
"1","(-4475,1225)","0","mstr_symbols","I57";
;
HDL_POWER"PVSA_CPU1"
BODY_TYPE"PLUMBING"
CDS_LIB"mstr_symbols"
VOLTAGE"1.1V";
"G\NAC"30;
%"CAP"
"1","(-4475,950)","0","mstr_discrete","I58";
;
ROOM"PVCCIN_CPU1_DECAP_VR"
CDS_LOCATION"C8P5"
$SEC"1"
CDS_SEC"1"
BOM_COST"PROC"
CDS_LIB"mstr_discrete"
MATERIAL"X6S"
VOLTAGE"4V"
PACK_TYPE"0805LF"
TOLERANCE"20%"
VALUE"22UF"
PART_NUMBER"C95333-002"
LOCATION"C8P5";
"A"
$PN"1"30;
"B"
$PN"2"29;
%"CAP_A"
"1","(-4625,4425)","0","dev_discrete","I59";
;
ROOM"PVCCIN_CPU1_DECAP_VR"
$SEC"1"
CDS_SEC"1"
CDS_LIB"dev_discrete"
BOM_COST"PROC"
CDS_LOCATION"C2D12"
MATERIAL"X6S"
VOLTAGE"4V"
PACK_TYPE"0603V"
TOLERANCE"20%"
VALUE"22.0UF"
PART_NUMBER"E15431-004"
LOCATION"C2D12";
"B"
$PN"2"31;
"A"
$PN"1"6;
%"GND"
"1","(-4325,4125)","0","mstr_symbols","I60";
;
HDL_POWER"GND"
ROOM"PVCCIN_CPU1_DECAP_VR"
BODY_TYPE"PLUMBING"
SIZE"1B"
CDS_LIB"mstr_symbols"
VOLTAGE"0";
"A\NAC"31;
%"CAP_A"
"1","(-4950,4450)","0","dev_discrete","I61";
;
ROOM"PVCCIN_CPU1_DECAP_VR"
$SEC"1"
CDS_SEC"1"
CDS_LIB"dev_discrete"
BOM_COST"PROC"
CDS_LOCATION"C2D22"
MATERIAL"X6S"
VOLTAGE"4V"
PACK_TYPE"0603V"
TOLERANCE"20%"
VALUE"22.0UF"
PART_NUMBER"E15431-004"
LOCATION"C2D22";
"B"
$PN"2"31;
"A"
$PN"1"6;
%"CAP_A"
"1","(-5575,4450)","0","dev_discrete","I63";
;
ROOM"PVCCIN_CPU1_DECAP_VR"
$SEC"1"
CDS_SEC"1"
CDS_LIB"dev_discrete"
BOM_COST"PROC"
CDS_LOCATION"C2D31"
MATERIAL"X6S"
VOLTAGE"4V"
PACK_TYPE"0603V"
TOLERANCE"20%"
VALUE"22.0UF"
PART_NUMBER"E15431-004"
LOCATION"C2D31";
"B"
$PN"2"31;
"A"
$PN"1"6;
%"CAP_A"
"1","(-5900,4450)","0","dev_discrete","I65";
;
ROOM"PVCCIN_CPU1_DECAP_VR"
$SEC"1"
CDS_SEC"1"
CDS_LIB"dev_discrete"
BOM_COST"PROC"
CDS_LOCATION"C2D21"
MATERIAL"X6S"
VOLTAGE"4V"
PACK_TYPE"0603V"
TOLERANCE"20%"
VALUE"22.0UF"
PART_NUMBER"E15431-004"
LOCATION"C2D21";
"B"
$PN"2"31;
"A"
$PN"1"6;
%"CAP_A"
"1","(-6350,4450)","0","dev_discrete","I66";
;
ROOM"PVCCIN_CPU1_DECAP_VR"
$SEC"1"
CDS_SEC"1"
CDS_LIB"dev_discrete"
BOM_COST"PROC"
CDS_LOCATION"C2D27"
MATERIAL"X6S"
VOLTAGE"4V"
PACK_TYPE"0603V"
TOLERANCE"20%"
VALUE"22.0UF"
PART_NUMBER"E15431-004"
LOCATION"C2D27";
"B"
$PN"2"32;
"A"
$PN"1"33;
%"GND"
"1","(-6350,4125)","0","mstr_symbols","I67";
;
HDL_POWER"GND"
ROOM"PVCCIN_CPU1_DECAP_VR"
BODY_TYPE"PLUMBING"
SIZE"1B"
CDS_LIB"mstr_symbols"
VOLTAGE"0";
"A\NAC"32;
%"CAP_A"
"1","(-7050,4450)","0","dev_discrete","I69";
;
ROOM"PVCCIN_CPU1_DECAP_VR"
$SEC"1"
CDS_SEC"1"
CDS_LIB"dev_discrete"
BOM_COST"PROC"
CDS_LOCATION"C3D2"
MATERIAL"X6S"
VOLTAGE"4V"
PACK_TYPE"0603V"
TOLERANCE"20%"
VALUE"22.0UF"
PART_NUMBER"E15431-004"
LOCATION"C3D2";
"B"
$PN"2"32;
"A"
$PN"1"33;
%"CAP_A"
"1","(-2450,4450)","0","dev_discrete","I7";
;
ROOM"PVCCIN_CPU1_DECAP_VR"
$SEC"1"
CDS_SEC"1"
CDS_LIB"dev_discrete"
BOM_COST"PROC"
CDS_LOCATION"C3D11"
MATERIAL"X6S"
VOLTAGE"4V"
PACK_TYPE"0603V"
TOLERANCE"20%"
VALUE"22.0UF"
PART_NUMBER"E15431-004"
LOCATION"C3D11";
"B"
$PN"2"21;
"A"
$PN"1"18;
%"CAP_A"
"1","(-7375,4450)","0","dev_discrete","I70";
;
ROOM"PVCCIN_CPU1_DECAP_VR"
$SEC"1"
CDS_SEC"1"
CDS_LIB"dev_discrete"
BOM_COST"PROC"
CDS_LOCATION"C2D36"
MATERIAL"X6S"
VOLTAGE"4V"
PACK_TYPE"0603V"
TOLERANCE"20%"
VALUE"22.0UF"
PART_NUMBER"E15431-004"
LOCATION"C2D36";
"B"
$PN"2"32;
"A"
$PN"1"33;
%"PVCCIN_CPU1"
"1","(-7725,4725)","0","mstr_symbols","I71";
;
HDL_POWER"PVCCIN_CPU1"
ROOM"PVCCIN_CPU1_DECAP_VR"
BODY_TYPE"PLUMBING"
CDS_LIB"mstr_symbols"
VOLTAGE"2.0V";
"G\NAC"33;
%"CAP_A"
"1","(-4625,3750)","0","dev_discrete","I73";
;
ROOM"PVCCIN_CPU1_DECAP_VR"
$SEC"1"
CDS_SEC"1"
CDS_LIB"dev_discrete"
BOM_COST"PROC"
CDS_LOCATION"C2D13"
MATERIAL"X6S"
VOLTAGE"4V"
PACK_TYPE"0603V"
TOLERANCE"20%"
VALUE"22.0UF"
PART_NUMBER"E15431-004"
LOCATION"C2D13";
"B"
$PN"2"34;
"A"
$PN"1"9;
%"GND"
"1","(-4325,3450)","0","mstr_symbols","I74";
;
HDL_POWER"GND"
ROOM"PVCCIN_CPU1_DECAP_VR"
BODY_TYPE"PLUMBING"
CDS_LIB"mstr_symbols"
SIZE"1B"
VOLTAGE"0";
"A\NAC"34;
%"CAP_A"
"1","(-4900,3775)","0","dev_discrete","I75";
;
ROOM"PVCCIN_CPU1_DECAP_VR"
$SEC"1"
CDS_SEC"1"
CDS_LIB"dev_discrete"
BOM_COST"PROC"
CDS_LOCATION"C2D19"
MATERIAL"X6S"
VOLTAGE"4V"
PACK_TYPE"0603V"
TOLERANCE"20%"
VALUE"22.0UF"
PART_NUMBER"E15431-004"
LOCATION"C2D19";
"B"
$PN"2"34;
"A"
$PN"1"9;
%"CAP_A"
"1","(-4600,3150)","0","dev_discrete","I76";
;
ROOM"PVCCIN_CPU1_DECAP_VR"
$SEC"1"
CDS_SEC"1"
CDS_LIB"dev_discrete"
BOM_COST"PROC"
CDS_LOCATION"C2D14"
MATERIAL"X6S"
VOLTAGE"4V"
PACK_TYPE"0603V"
TOLERANCE"20%"
VALUE"22.0UF"
PART_NUMBER"E15431-004"
LOCATION"C2D14";
"B"
$PN"2"35;
"A"
$PN"1"10;
%"GND"
"1","(-4325,2850)","0","mstr_symbols","I77";
;
HDL_POWER"GND"
ROOM"PVCCIN_CPU1_DECAP_VR"
BODY_TYPE"PLUMBING"
CDS_LIB"mstr_symbols"
SIZE"1B"
VOLTAGE"0";
"A\NAC"35;
%"CAP_A"
"1","(-4875,3125)","0","dev_discrete","I79";
;
ROOM"PVCCIN_CPU1_DECAP_VR"
$SEC"1"
CDS_SEC"1"
CDS_LIB"dev_discrete"
BOM_COST"PROC"
CDS_LOCATION"C2D20"
MATERIAL"X6S"
VOLTAGE"4V"
PACK_TYPE"0603V"
TOLERANCE"20%"
VALUE"22.0UF"
PART_NUMBER"E15431-004"
LOCATION"C2D20";
"B"
$PN"2"35;
"A"
$PN"1"10;
%"CAP_A"
"1","(-2975,4450)","0","dev_discrete","I8";
;
ROOM"PVCCIN_CPU1_DECAP_VR"
$SEC"1"
CDS_SEC"1"
CDS_LIB"dev_discrete"
BOM_COST"PROC"
CDS_LOCATION"C3D13"
MATERIAL"X6S"
VOLTAGE"4V"
PACK_TYPE"0603V"
TOLERANCE"20%"
VALUE"22.0UF"
PART_NUMBER"E15431-004"
LOCATION"C3D13";
"B"
$PN"2"21;
"A"
$PN"1"18;
%"CAP_A"
"1","(-5200,3150)","0","dev_discrete","I80";
;
ROOM"PVCCIN_CPU1_DECAP_VR"
$SEC"1"
CDS_SEC"1"
CDS_LIB"dev_discrete"
BOM_COST"PROC"
CDS_LOCATION"C2D24"
MATERIAL"X6S"
VOLTAGE"4V"
PACK_TYPE"0603V"
TOLERANCE"20%"
VALUE"22.0UF"
PART_NUMBER"E15431-004"
LOCATION"C2D24";
"B"
$PN"2"35;
"A"
$PN"1"10;
%"CAP_A"
"1","(-5225,3775)","0","dev_discrete","I82";
;
ROOM"PVCCIN_CPU1_DECAP_VR"
$SEC"1"
CDS_SEC"1"
CDS_LIB"dev_discrete"
BOM_COST"PROC"
CDS_LOCATION"C2D25"
MATERIAL"X6S"
VOLTAGE"4V"
PACK_TYPE"0603V"
TOLERANCE"20%"
VALUE"22.0UF"
PART_NUMBER"E15431-004"
LOCATION"C2D25";
"B"
$PN"2"34;
"A"
$PN"1"9;
%"CAP_A"
"1","(-5550,3775)","0","dev_discrete","I83";
;
ROOM"PVCCIN_CPU1_DECAP_VR"
$SEC"1"
CDS_SEC"1"
CDS_LIB"dev_discrete"
BOM_COST"PROC"
CDS_LOCATION"C2D30"
MATERIAL"X6S"
VOLTAGE"4V"
PACK_TYPE"0603V"
TOLERANCE"20%"
VALUE"22.0UF"
PART_NUMBER"E15431-004"
LOCATION"C2D30";
"B"
$PN"2"34;
"A"
$PN"1"9;
%"CAP_A"
"1","(-5875,3775)","0","dev_discrete","I85";
;
ROOM"PVCCIN_CPU1_DECAP_VR"
$SEC"1"
CDS_SEC"1"
CDS_LIB"dev_discrete"
BOM_COST"PROC"
CDS_LOCATION"C2D33"
MATERIAL"X6S"
VOLTAGE"4V"
PACK_TYPE"0603V"
TOLERANCE"20%"
VALUE"22.0UF"
PART_NUMBER"E15431-004"
LOCATION"C2D33";
"B"
$PN"2"34;
"A"
$PN"1"9;
%"CAP"
"1","(-5425,2200)","0","mstr_discrete","I88";
;
ROOM"PVCCIN_CPU1_DECAP_VR"
CDS_LOCATION"C8P4"
$SEC"1"
CDS_SEC"1"
BOM_COST"PROC"
CDS_LIB"mstr_discrete"
MATERIAL"X6S"
VOLTAGE"4V"
PACK_TYPE"0805"
TOLERANCE"20%"
VALUE"47UF"
PART_NUMBER"C95333-006"
LOCATION"C8P4";
"A"
$PN"1"11;
"B"
$PN"2"36;
%"CAP"
"1","(-5700,2200)","0","mstr_discrete","I89";
;
ROOM"PVCCIN_CPU1_DECAP_VR"
CDS_LOCATION"C8P20"
$SEC"1"
CDS_SEC"1"
BOM_COST"PROC"
CDS_LIB"mstr_discrete"
MATERIAL"X6S"
VOLTAGE"4V"
PACK_TYPE"0805"
TOLERANCE"20%"
VALUE"47UF"
PART_NUMBER"C95333-006"
LOCATION"C8P20";
"A"
$PN"1"11;
"B"
$PN"2"36;
%"CAP_A"
"1","(-5850,3150)","0","dev_discrete","I90";
;
ROOM"PVCCIN_CPU1_DECAP_VR"
$SEC"1"
CDS_SEC"1"
CDS_LIB"dev_discrete"
BOM_COST"PROC"
CDS_LOCATION"C2D32"
MATERIAL"X6S"
VOLTAGE"4V"
PACK_TYPE"0603V"
TOLERANCE"20%"
VALUE"22.0UF"
PART_NUMBER"E15431-004"
LOCATION"C2D32";
"B"
$PN"2"35;
"A"
$PN"1"10;
%"CAP"
"1","(-5975,2200)","0","mstr_discrete","I92";
;
ROOM"PVCCIN_CPU1_DECAP_VR"
CDS_LOCATION"C8P18"
$SEC"1"
CDS_SEC"1"
CDS_LIB"mstr_discrete"
BOM_COST"PROC"
MATERIAL"X6S"
VOLTAGE"4V"
PACK_TYPE"0805"
TOLERANCE"20%"
VALUE"47UF"
PART_NUMBER"C95333-006"
LOCATION"C8P18";
"A"
$PN"1"11;
"B"
$PN"2"36;
%"GND"
"1","(-5150,1825)","0","mstr_symbols","I93";
;
HDL_POWER"GND"
ROOM"PVCCIN_CPU1_DECAP_VR"
BODY_TYPE"PLUMBING"
CDS_LIB"mstr_symbols"
SIZE"1B"
VOLTAGE"0";
"A\NAC"36;
%"GND"
"1","(-5300,1225)","0","mstr_symbols","I95";
;
HDL_POWER"GND"
ROOM"PVCCIN_CPU1_DECAP_VR"
BODY_TYPE"PLUMBING"
SIZE"1B"
CDS_LIB"mstr_symbols"
VOLTAGE"0";
"A\NAC"37;
%"GND"
"1","(-5275,575)","0","mstr_symbols","I97";
;
HDL_POWER"GND"
ROOM"PVCCIN_CPU1_DECAP_VR"
BODY_TYPE"PLUMBING"
CDS_LIB"mstr_symbols"
SIZE"1B"
VOLTAGE"0";
"A\NAC"38;
END.
